FILE_TYPE = CONNECTIVITY;
{Allegro Design Entry HDL 17.4-2019 S026 (4007227) 1/17/2022}
"PAGE_NUMBER" = 88;
0"NC";
1"GND\g";
2"GND\g";
3"P3V3\g";
4"M_D_CPU0_SA_DQ<31:0>";
5"M_D_CPU0_SA_DQS_DN<9:0>";
6"M_D_CPU0_SB_DQS_DP<9:0>";
7"M_D_CPU0_SB_DQS_DN<9:0>";
8"M_D_CPU0_SA_DQS_DP<9:0>";
9"M_D_CPU0_SA_CA<6:0>";
10"M_D_CPU0_SB_DQ<31:0>";
11"M_D_CPU0_SB_CB<7:0>";
12"M_D_CPU0_SA_CB<7:0>";
13"M_D_CPU0_SB_CA<6:0>";
14"M_D_CPU0_SB_CB<0>";
15"I3C_SPD_DDRAF_CPU0_SCL";
16"M_D_CPU0_RESET_N";
17"I3C_SPD_DDRD_CPU0_SCL";
18"P12V_MEM_CPU0\g";
19"GND\g";
20"GND\g";
21"GND\g";
22"PD_CHD_CPU0_DIMM_SAA";
23"M_D_CPU0_SA_CB<7>";
24"M_D_CPU0_SA_CB<4>";
25"M_D_CPU0_SA_CB<1>";
26"M_D_CPU0_SB_CB<7>";
27"M_D_CPU0_SA_CA<0>";
28"M_D_CPU0_SB_CA<0>";
29"M_D_CPU0_SA_CA<1>";
30"M_D_CPU0_SB_CA<1>";
31"M_D_CPU0_SA_CA<2>";
32"M_D_CPU0_SB_CA<2>";
33"M_D_CPU0_SA_CA<3>";
34"M_D_CPU0_SB_CA<3>";
35"M_D_CPU0_SA_CA<4>";
36"M_D_CPU0_SB_CA<4>";
37"M_D_CPU0_SA_CA<5>";
38"M_D_CPU0_SB_CA<5>";
39"M_D_CPU0_SB_CA<6>";
40"M_D_CPU0_SA_CB<6>";
41"M_D_CPU0_SA_CB<5>";
42"M_D_CPU0_SA_CB<3>";
43"M_D_CPU0_SA_CB<2>";
44"M_D_CPU0_SA_CB<0>";
45"M_D_CPU0_SB_CB<6>";
46"M_D_CPU0_SB_CB<5>";
47"M_D_CPU0_SB_CB<4>";
48"M_D_CPU0_SB_CB<3>";
49"M_D_CPU0_SB_CB<2>";
50"M_D_CPU0_SB_CB<1>";
51"M_D_CPU0_CLK_DN<0>";
52"M_D_CPU0_CLK_DP<0>";
53"M_D_CPU0_SA_CS_N<0>";
54"M_D_CPU0_SB_CS_N<0>";
55"M_D_CPU0_SA_CS_N<1>";
56"M_D_CPU0_SB_CS_N<1>";
57"M_D_CPU0_SA_DQ<30>";
58"M_D_CPU0_SA_DQ<28>";
59"M_D_CPU0_SA_DQ<27>";
60"M_D_CPU0_SA_DQ<25>";
61"M_D_CPU0_SA_DQ<24>";
62"M_D_CPU0_SA_DQ<23>";
63"M_D_CPU0_SA_DQ<22>";
64"M_D_CPU0_SA_DQ<21>";
65"M_D_CPU0_SA_DQ<20>";
66"M_D_CPU0_SA_DQ<19>";
67"M_D_CPU0_SA_DQ<18>";
68"M_D_CPU0_SA_DQ<17>";
69"M_D_CPU0_SA_DQ<16>";
70"M_D_CPU0_SA_DQ<15>";
71"M_D_CPU0_SA_DQ<14>";
72"M_D_CPU0_SA_DQ<13>";
73"M_D_CPU0_SA_DQ<11>";
74"M_D_CPU0_SA_DQ<10>";
75"M_D_CPU0_SA_DQ<5>";
76"M_D_CPU0_SA_DQ<4>";
77"M_D_CPU0_SA_DQ<3>";
78"M_D_CPU0_SA_DQ<2>";
79"M_D_CPU0_SA_DQ<1>";
80"M_D_CPU0_SA_DQ<0>";
81"M_D_CPU0_SB_DQ<31>";
82"M_D_CPU0_SB_DQ<30>";
83"M_D_CPU0_SB_DQ<29>";
84"M_D_CPU0_SB_DQ<28>";
85"M_D_CPU0_SB_DQ<27>";
86"M_D_CPU0_SB_DQ<26>";
87"M_D_CPU0_SB_DQ<25>";
88"M_D_CPU0_SB_DQ<24>";
89"M_D_CPU0_SB_DQ<23>";
90"M_D_CPU0_SB_DQ<22>";
91"M_D_CPU0_SB_DQ<21>";
92"M_D_CPU0_SB_DQ<20>";
93"M_D_CPU0_SB_DQ<19>";
94"M_D_CPU0_SB_DQ<18>";
95"M_D_CPU0_SB_DQ<17>";
96"M_D_CPU0_SB_DQ<16>";
97"M_D_CPU0_SB_DQ<15>";
98"M_D_CPU0_SB_DQ<14>";
99"M_D_CPU0_SB_DQ<13>";
100"M_D_CPU0_SB_DQ<12>";
101"M_D_CPU0_SB_DQ<11>";
102"M_D_CPU0_SB_DQ<10>";
103"M_D_CPU0_SB_DQ<9>";
104"M_D_CPU0_SB_DQ<8>";
105"M_D_CPU0_SB_DQ<7>";
106"M_D_CPU0_SB_DQ<6>";
107"M_D_CPU0_SB_DQ<5>";
108"M_D_CPU0_SB_DQ<4>";
109"M_D_CPU0_SB_DQ<3>";
110"M_D_CPU0_SB_DQ<2>";
111"M_D_CPU0_SB_DQ<1>";
112"M_D_CPU0_SB_DQ<0>";
113"M_D_CPU0_SB_RSP<0>";
114"M_D_CPU0_SB_PAR";
115"M_D_CPU0_SA_DQ<26>";
116"M_D_CPU0_SA_DQ<31>";
117"M_D_CPU0_SA_CA<6>";
118"M_D_CPU0_SA_DQS_DN<7>";
119"M_D_CPU0_SA_DQS_DP<6>";
120"M_D_CPU0_SB_DQS_DN<8>";
121"M_D_CPU0_SB_DQS_DP<7>";
122"M_D_CPU0_SA_DQS_DP<0>";
123"M_D_CPU0_SB_DQS_DN<0>";
124"M_D_CPU0_SB_DQS_DP<0>";
125"M_D_CPU0_SB_DQS_DN<1>";
126"M_D_CPU0_SB_DQS_DP<1>";
127"M_D_CPU0_SA_DQS_DN<2>";
128"M_D_CPU0_SA_DQS_DP<2>";
129"M_D_CPU0_SB_DQS_DN<2>";
130"M_D_CPU0_SB_DQS_DP<2>";
131"M_D_CPU0_SA_DQS_DN<3>";
132"M_D_CPU0_SA_DQS_DP<3>";
133"M_D_CPU0_SB_DQS_DN<3>";
134"M_D_CPU0_SB_DQS_DP<3>";
135"M_D_CPU0_SA_DQS_DN<4>";
136"M_D_CPU0_SA_DQS_DP<4>";
137"M_D_CPU0_SB_DQS_DN<4>";
138"M_D_CPU0_SB_DQS_DP<4>";
139"M_D_CPU0_SA_DQS_DN<5>";
140"M_D_CPU0_SA_DQS_DP<5>";
141"M_D_CPU0_SB_DQS_DN<5>";
142"M_D_CPU0_SB_DQS_DP<5>";
143"M_D_CPU0_SA_DQS_DN<6>";
144"M_D_CPU0_SB_DQS_DN<6>";
145"M_D_CPU0_SB_DQS_DP<6>";
146"M_D_CPU0_SA_DQS_DP<7>";
147"M_D_CPU0_SB_DQS_DN<7>";
148"M_D_CPU0_SA_DQS_DN<8>";
149"M_D_CPU0_SA_DQS_DP<8>";
150"M_D_CPU0_SA_DQS_DP<9>";
151"M_D_CPU0_SA_DQS_DP<1>";
152"M_D_CPU0_SA_DQS_DN<1>";
153"M_D_CPU0_SA_DQS_DN<0>";
154"M_D_CPU0_SB_DQS_DP<9>";
155"M_D_CPU0_SB_DQS_DN<9>";
156"M_D_CPU0_SB_DQS_DP<8>";
157"M_D_CPU0_SA_DQS_DN<9>";
158"M_D_CPU0_SA_DQ<6>";
159"M_D_CPU0_SA_DQ<7>";
160"M_D_CPU0_SA_DQ<8>";
161"M_D_CPU0_SA_DQ<9>";
162"M_D_CPU0_SA_DQ<12>";
163"M_D_CPU0_SA_DQ<29>";
164"M_D_CPU0_SA_PAR";
165"M_D_CPU0_SA_RSP<0>";
166"PWRGD_CHD_CPU0_DIMM";
167"PWRGD_CHAF_CPU0";
168"I3C_SPD_DDRAF_CPU0_SDA";
169"M_D_CPU0_ALERT_N";
170"I3C_SPD_DDRD_CPU0_SDA";
171"PD_CHD_CPU0_DIMM_SAA";
172"P3V3_AUX\g";
%"GND"
"1","(-2250,1950)","0","mstr_symbols","I150";
;
CDS_LIB"mstr_symbols"
SIZE"1B"
VOLTAGE"0.0"
BODY_TYPE"PLUMBING"
HDL_POWER"GND";
"A\NAC"21;
%"GND"
"1","(-450,1750)","0","mstr_symbols","I152";
;
CDS_LIB"mstr_symbols"
SIZE"1B"
VOLTAGE"0.0"
BODY_TYPE"PLUMBING"
HDL_POWER"GND";
"A\NAC"20;
%"VCC_CORE"
"1","(-8475,3625)","0","mstr_symbols","I175";
;
HDL_POWER"P3V3_AUX"
CDS_LIB"mstr_symbols"
VOLTAGE"3.3"
ROOM"PVCCINFAON_CPU0_CTRL";
"A"172;
%"TAP"
"1","(-7775,3350)","2","mstr_standard","I189";
;
CDS_LIB"mstr_standard"
BODY_TYPE"PLUMBING"
HDL_TAP"TRUE";
"B \NAC \NWC"11;
"S \NAC"
BN"0"14;
%"TAP"
"1","(-7775,3400)","2","mstr_standard","I190";
;
CDS_LIB"mstr_standard"
BODY_TYPE"PLUMBING"
HDL_TAP"TRUE";
"B \NAC \NWC"11;
"S \NAC"
BN"1"50;
%"TAP"
"1","(-7775,3500)","2","mstr_standard","I191";
;
CDS_LIB"mstr_standard"
BODY_TYPE"PLUMBING"
HDL_TAP"TRUE";
"B \NAC \NWC"11;
"S \NAC"
BN"3"48;
%"TAP"
"1","(-7775,3450)","2","mstr_standard","I192";
;
CDS_LIB"mstr_standard"
BODY_TYPE"PLUMBING"
HDL_TAP"TRUE";
"B \NAC \NWC"11;
"S \NAC"
BN"2"49;
%"TAP"
"1","(-7775,3550)","2","mstr_standard","I193";
;
CDS_LIB"mstr_standard"
BODY_TYPE"PLUMBING"
HDL_TAP"TRUE";
"B \NAC \NWC"11;
"S \NAC"
BN"4"47;
%"TAP"
"1","(-7775,3600)","2","mstr_standard","I194";
;
CDS_LIB"mstr_standard"
BODY_TYPE"PLUMBING"
HDL_TAP"TRUE";
"B \NAC \NWC"11;
"S \NAC"
BN"5"46;
%"TAP"
"1","(-7775,3650)","2","mstr_standard","I195";
;
CDS_LIB"mstr_standard"
BODY_TYPE"PLUMBING"
HDL_TAP"TRUE";
"B \NAC \NWC"11;
"S \NAC"
BN"6"45;
%"TAP"
"1","(-7775,3700)","2","mstr_standard","I196";
;
CDS_LIB"mstr_standard"
BODY_TYPE"PLUMBING"
HDL_TAP"TRUE";
"B \NAC \NWC"11;
"S \NAC"
BN"7"26;
%"TAP"
"1","(-7775,3800)","2","mstr_standard","I197";
;
CDS_LIB"mstr_standard"
BODY_TYPE"PLUMBING"
HDL_TAP"TRUE";
"B \NAC \NWC"12;
"S \NAC"
BN"0"44;
%"TAP"
"1","(-7775,3850)","2","mstr_standard","I198";
;
CDS_LIB"mstr_standard"
BODY_TYPE"PLUMBING"
HDL_TAP"TRUE";
"B \NAC \NWC"12;
"S \NAC"
BN"1"25;
%"TAP"
"1","(-7775,3950)","2","mstr_standard","I199";
;
CDS_LIB"mstr_standard"
BODY_TYPE"PLUMBING"
HDL_TAP"TRUE";
"B \NAC \NWC"12;
"S \NAC"
BN"3"42;
%"TAP"
"1","(-7775,3900)","2","mstr_standard","I200";
;
CDS_LIB"mstr_standard"
BODY_TYPE"PLUMBING"
HDL_TAP"TRUE";
"B \NAC \NWC"12;
"S \NAC"
BN"2"43;
%"TAP"
"1","(-7775,4000)","2","mstr_standard","I201";
;
CDS_LIB"mstr_standard"
BODY_TYPE"PLUMBING"
HDL_TAP"TRUE";
"B \NAC \NWC"12;
"S \NAC"
BN"4"24;
%"TAP"
"1","(-7775,4050)","2","mstr_standard","I202";
;
CDS_LIB"mstr_standard"
BODY_TYPE"PLUMBING"
HDL_TAP"TRUE";
"B \NAC \NWC"12;
"S \NAC"
BN"5"41;
%"TAP"
"1","(-7775,4100)","2","mstr_standard","I203";
;
CDS_LIB"mstr_standard"
BODY_TYPE"PLUMBING"
HDL_TAP"TRUE";
"B \NAC \NWC"12;
"S \NAC"
BN"6"40;
%"TAP"
"1","(-6075,2350)","0","mstr_standard","I204";
;
CDS_LIB"mstr_standard"
BODY_TYPE"PLUMBING"
HDL_TAP"TRUE";
"B \NAC \NWC"10;
"S \NAC"
BN"0"112;
%"TAP"
"1","(-6075,2400)","0","mstr_standard","I205";
;
CDS_LIB"mstr_standard"
BODY_TYPE"PLUMBING"
HDL_TAP"TRUE";
"B \NAC \NWC"10;
"S \NAC"
BN"1"111;
%"TAP"
"1","(-6075,2450)","0","mstr_standard","I206";
;
CDS_LIB"mstr_standard"
BODY_TYPE"PLUMBING"
HDL_TAP"TRUE";
"B \NAC \NWC"10;
"S \NAC"
BN"2"110;
%"TAP"
"1","(-6075,2500)","0","mstr_standard","I207";
;
CDS_LIB"mstr_standard"
BODY_TYPE"PLUMBING"
HDL_TAP"TRUE";
"B \NAC \NWC"10;
"S \NAC"
BN"3"109;
%"TAP"
"1","(-6075,2550)","0","mstr_standard","I208";
;
CDS_LIB"mstr_standard"
BODY_TYPE"PLUMBING"
HDL_TAP"TRUE";
"B \NAC \NWC"10;
"S \NAC"
BN"4"108;
%"TAP"
"1","(-6075,2600)","0","mstr_standard","I209";
;
CDS_LIB"mstr_standard"
BODY_TYPE"PLUMBING"
HDL_TAP"TRUE";
"B \NAC \NWC"10;
"S \NAC"
BN"5"107;
%"TAP"
"1","(-6075,2700)","0","mstr_standard","I210";
;
CDS_LIB"mstr_standard"
BODY_TYPE"PLUMBING"
HDL_TAP"TRUE";
"B \NAC \NWC"10;
"S \NAC"
BN"7"105;
%"TAP"
"1","(-6075,2650)","0","mstr_standard","I211";
;
CDS_LIB"mstr_standard"
BODY_TYPE"PLUMBING"
HDL_TAP"TRUE";
"B \NAC \NWC"10;
"S \NAC"
BN"6"106;
%"TAP"
"1","(-6075,2750)","0","mstr_standard","I212";
;
CDS_LIB"mstr_standard"
BODY_TYPE"PLUMBING"
HDL_TAP"TRUE";
"B \NAC \NWC"10;
"S \NAC"
BN"8"104;
%"TAP"
"1","(-6075,2800)","0","mstr_standard","I213";
;
CDS_LIB"mstr_standard"
BODY_TYPE"PLUMBING"
HDL_TAP"TRUE";
"B \NAC \NWC"10;
"S \NAC"
BN"9"103;
%"TAP"
"1","(-6075,2850)","0","mstr_standard","I214";
;
CDS_LIB"mstr_standard"
BODY_TYPE"PLUMBING"
HDL_TAP"TRUE";
"B \NAC \NWC"10;
"S \NAC"
BN"10"102;
%"TAP"
"1","(-6075,2950)","0","mstr_standard","I215";
;
CDS_LIB"mstr_standard"
BODY_TYPE"PLUMBING"
HDL_TAP"TRUE";
"B \NAC \NWC"10;
"S \NAC"
BN"12"100;
%"TAP"
"1","(-6075,2900)","0","mstr_standard","I216";
;
CDS_LIB"mstr_standard"
BODY_TYPE"PLUMBING"
HDL_TAP"TRUE";
"B \NAC \NWC"10;
"S \NAC"
BN"11"101;
%"TAP"
"1","(-6075,3100)","0","mstr_standard","I217";
;
CDS_LIB"mstr_standard"
BODY_TYPE"PLUMBING"
HDL_TAP"TRUE";
"B \NAC \NWC"10;
"S \NAC"
BN"15"97;
%"TAP"
"1","(-6075,3050)","0","mstr_standard","I218";
;
CDS_LIB"mstr_standard"
BODY_TYPE"PLUMBING"
HDL_TAP"TRUE";
"B \NAC \NWC"10;
"S \NAC"
BN"14"98;
%"TAP"
"1","(-6075,3000)","0","mstr_standard","I219";
;
CDS_LIB"mstr_standard"
BODY_TYPE"PLUMBING"
HDL_TAP"TRUE";
"B \NAC \NWC"10;
"S \NAC"
BN"13"99;
%"TAP"
"1","(-6075,3250)","0","mstr_standard","I220";
;
CDS_LIB"mstr_standard"
BODY_TYPE"PLUMBING"
HDL_TAP"TRUE";
"B \NAC \NWC"10;
"S \NAC"
BN"18"94;
%"TAP"
"1","(-6075,3200)","0","mstr_standard","I221";
;
CDS_LIB"mstr_standard"
BODY_TYPE"PLUMBING"
HDL_TAP"TRUE";
"B \NAC \NWC"10;
"S \NAC"
BN"17"95;
%"TAP"
"1","(-6075,3150)","0","mstr_standard","I222";
;
CDS_LIB"mstr_standard"
BODY_TYPE"PLUMBING"
HDL_TAP"TRUE";
"B \NAC \NWC"10;
"S \NAC"
BN"16"96;
%"TAP"
"1","(-6075,3350)","0","mstr_standard","I223";
;
CDS_LIB"mstr_standard"
BODY_TYPE"PLUMBING"
HDL_TAP"TRUE";
"B \NAC \NWC"10;
"S \NAC"
BN"20"92;
%"TAP"
"1","(-6075,3300)","0","mstr_standard","I224";
;
CDS_LIB"mstr_standard"
BODY_TYPE"PLUMBING"
HDL_TAP"TRUE";
"B \NAC \NWC"10;
"S \NAC"
BN"19"93;
%"TAP"
"1","(-6075,3400)","0","mstr_standard","I225";
;
CDS_LIB"mstr_standard"
BODY_TYPE"PLUMBING"
HDL_TAP"TRUE";
"B \NAC \NWC"10;
"S \NAC"
BN"21"91;
%"TAP"
"1","(-6075,3450)","0","mstr_standard","I226";
;
CDS_LIB"mstr_standard"
BODY_TYPE"PLUMBING"
HDL_TAP"TRUE";
"B \NAC \NWC"10;
"S \NAC"
BN"22"90;
%"TAP"
"1","(-6075,3500)","0","mstr_standard","I227";
;
CDS_LIB"mstr_standard"
BODY_TYPE"PLUMBING"
HDL_TAP"TRUE";
"B \NAC \NWC"10;
"S \NAC"
BN"23"89;
%"TAP"
"1","(-6075,3550)","0","mstr_standard","I228";
;
CDS_LIB"mstr_standard"
BODY_TYPE"PLUMBING"
HDL_TAP"TRUE";
"B \NAC \NWC"10;
"S \NAC"
BN"24"88;
%"TAP"
"1","(-6075,3600)","0","mstr_standard","I229";
;
CDS_LIB"mstr_standard"
BODY_TYPE"PLUMBING"
HDL_TAP"TRUE";
"B \NAC \NWC"10;
"S \NAC"
BN"25"87;
%"TAP"
"1","(-6075,3650)","0","mstr_standard","I230";
;
CDS_LIB"mstr_standard"
BODY_TYPE"PLUMBING"
HDL_TAP"TRUE";
"B \NAC \NWC"10;
"S \NAC"
BN"26"86;
%"TAP"
"1","(-6075,3700)","0","mstr_standard","I231";
;
CDS_LIB"mstr_standard"
BODY_TYPE"PLUMBING"
HDL_TAP"TRUE";
"B \NAC \NWC"10;
"S \NAC"
BN"27"85;
%"TAP"
"1","(-6075,3750)","0","mstr_standard","I232";
;
CDS_LIB"mstr_standard"
BODY_TYPE"PLUMBING"
HDL_TAP"TRUE";
"B \NAC \NWC"10;
"S \NAC"
BN"28"84;
%"TAP"
"1","(-6075,3800)","0","mstr_standard","I233";
;
CDS_LIB"mstr_standard"
BODY_TYPE"PLUMBING"
HDL_TAP"TRUE";
"B \NAC \NWC"10;
"S \NAC"
BN"29"83;
%"TAP"
"1","(-6075,3850)","0","mstr_standard","I234";
;
CDS_LIB"mstr_standard"
BODY_TYPE"PLUMBING"
HDL_TAP"TRUE";
"B \NAC \NWC"10;
"S \NAC"
BN"30"82;
%"TAP"
"1","(-6075,4000)","0","mstr_standard","I235";
;
CDS_LIB"mstr_standard"
BODY_TYPE"PLUMBING"
HDL_TAP"TRUE";
"B \NAC \NWC"4;
"S \NAC"
BN"0"80;
%"TAP"
"1","(-6075,3900)","0","mstr_standard","I236";
;
CDS_LIB"mstr_standard"
BODY_TYPE"PLUMBING"
HDL_TAP"TRUE";
"B \NAC \NWC"10;
"S \NAC"
BN"31"81;
%"TAP"
"1","(-6075,4050)","0","mstr_standard","I237";
;
CDS_LIB"mstr_standard"
BODY_TYPE"PLUMBING"
HDL_TAP"TRUE";
"B \NAC \NWC"4;
"S \NAC"
BN"1"79;
%"TAP"
"1","(-6075,4100)","0","mstr_standard","I238";
;
CDS_LIB"mstr_standard"
BODY_TYPE"PLUMBING"
HDL_TAP"TRUE";
"B \NAC \NWC"4;
"S \NAC"
BN"2"78;
%"TAP"
"1","(-7775,4150)","2","mstr_standard","I239";
;
CDS_LIB"mstr_standard"
BODY_TYPE"PLUMBING"
HDL_TAP"TRUE";
"B \NAC \NWC"12;
"S \NAC"
BN"7"23;
%"TAP"
"1","(-7775,4850)","2","mstr_standard","I240";
;
CDS_LIB"mstr_standard"
BODY_TYPE"PLUMBING"
HDL_TAP"TRUE";
"B \NAC \NWC"13;
"S \NAC"
BN"0"28;
%"TAP"
"1","(-7775,4900)","2","mstr_standard","I241";
;
CDS_LIB"mstr_standard"
BODY_TYPE"PLUMBING"
HDL_TAP"TRUE";
"B \NAC \NWC"13;
"S \NAC"
BN"1"30;
%"TAP"
"1","(-7775,4950)","2","mstr_standard","I242";
;
CDS_LIB"mstr_standard"
BODY_TYPE"PLUMBING"
HDL_TAP"TRUE";
"B \NAC \NWC"13;
"S \NAC"
BN"2"32;
%"TAP"
"1","(-7775,5000)","2","mstr_standard","I243";
;
CDS_LIB"mstr_standard"
BODY_TYPE"PLUMBING"
HDL_TAP"TRUE";
"B \NAC \NWC"13;
"S \NAC"
BN"3"34;
%"TAP"
"1","(-7775,5050)","2","mstr_standard","I244";
;
CDS_LIB"mstr_standard"
BODY_TYPE"PLUMBING"
HDL_TAP"TRUE";
"B \NAC \NWC"13;
"S \NAC"
BN"4"36;
%"TAP"
"1","(-7775,5100)","2","mstr_standard","I245";
;
CDS_LIB"mstr_standard"
BODY_TYPE"PLUMBING"
HDL_TAP"TRUE";
"B \NAC \NWC"13;
"S \NAC"
BN"5"38;
%"TAP"
"1","(-7775,5150)","2","mstr_standard","I246";
;
CDS_LIB"mstr_standard"
BODY_TYPE"PLUMBING"
HDL_TAP"TRUE";
"B \NAC \NWC"13;
"S \NAC"
BN"6"39;
%"TAP"
"1","(-7775,5250)","2","mstr_standard","I247";
;
CDS_LIB"mstr_standard"
BODY_TYPE"PLUMBING"
HDL_TAP"TRUE";
"B \NAC \NWC"9;
"S \NAC"
BN"0"27;
%"TAP"
"1","(-7775,5300)","2","mstr_standard","I248";
;
CDS_LIB"mstr_standard"
BODY_TYPE"PLUMBING"
HDL_TAP"TRUE";
"B \NAC \NWC"9;
"S \NAC"
BN"1"29;
%"TAP"
"1","(-7775,5350)","2","mstr_standard","I249";
;
CDS_LIB"mstr_standard"
BODY_TYPE"PLUMBING"
HDL_TAP"TRUE";
"B \NAC \NWC"9;
"S \NAC"
BN"2"31;
%"TAP"
"1","(-7775,5400)","2","mstr_standard","I250";
;
CDS_LIB"mstr_standard"
BODY_TYPE"PLUMBING"
HDL_TAP"TRUE";
"B \NAC \NWC"9;
"S \NAC"
BN"3"33;
%"TAP"
"1","(-7775,5450)","2","mstr_standard","I251";
;
CDS_LIB"mstr_standard"
BODY_TYPE"PLUMBING"
HDL_TAP"TRUE";
"B \NAC \NWC"9;
"S \NAC"
BN"4"35;
%"TAP"
"1","(-7775,5500)","2","mstr_standard","I252";
;
CDS_LIB"mstr_standard"
BODY_TYPE"PLUMBING"
HDL_TAP"TRUE";
"B \NAC \NWC"9;
"S \NAC"
BN"5"37;
%"TAP"
"1","(-7775,5550)","2","mstr_standard","I253";
;
CDS_LIB"mstr_standard"
BODY_TYPE"PLUMBING"
HDL_TAP"TRUE";
"B \NAC \NWC"9;
"S \NAC"
BN"6"117;
%"TAP"
"1","(-6075,4150)","0","mstr_standard","I254";
;
CDS_LIB"mstr_standard"
BODY_TYPE"PLUMBING"
HDL_TAP"TRUE";
"B \NAC \NWC"4;
"S \NAC"
BN"3"77;
%"TAP"
"1","(-6075,4200)","0","mstr_standard","I255";
;
CDS_LIB"mstr_standard"
BODY_TYPE"PLUMBING"
HDL_TAP"TRUE";
"B \NAC \NWC"4;
"S \NAC"
BN"4"76;
%"TAP"
"1","(-6075,4250)","0","mstr_standard","I256";
;
CDS_LIB"mstr_standard"
BODY_TYPE"PLUMBING"
HDL_TAP"TRUE";
"B \NAC \NWC"4;
"S \NAC"
BN"5"75;
%"TAP"
"1","(-6075,4350)","0","mstr_standard","I257";
;
CDS_LIB"mstr_standard"
BODY_TYPE"PLUMBING"
HDL_TAP"TRUE";
"B \NAC \NWC"4;
"S \NAC"
BN"7"159;
%"TAP"
"1","(-6075,4300)","0","mstr_standard","I258";
;
CDS_LIB"mstr_standard"
BODY_TYPE"PLUMBING"
HDL_TAP"TRUE";
"B \NAC \NWC"4;
"S \NAC"
BN"6"158;
%"TAP"
"1","(-6075,4400)","0","mstr_standard","I259";
;
CDS_LIB"mstr_standard"
BODY_TYPE"PLUMBING"
HDL_TAP"TRUE";
"B \NAC \NWC"4;
"S \NAC"
BN"8"160;
%"TAP"
"1","(-6075,4450)","0","mstr_standard","I260";
;
CDS_LIB"mstr_standard"
BODY_TYPE"PLUMBING"
HDL_TAP"TRUE";
"B \NAC \NWC"4;
"S \NAC"
BN"9"161;
%"TAP"
"1","(-6075,4500)","0","mstr_standard","I261";
;
CDS_LIB"mstr_standard"
BODY_TYPE"PLUMBING"
HDL_TAP"TRUE";
"B \NAC \NWC"4;
"S \NAC"
BN"10"74;
%"TAP"
"1","(-6075,4550)","0","mstr_standard","I262";
;
CDS_LIB"mstr_standard"
BODY_TYPE"PLUMBING"
HDL_TAP"TRUE";
"B \NAC \NWC"4;
"S \NAC"
BN"11"73;
%"TAP"
"1","(-6075,4600)","0","mstr_standard","I263";
;
CDS_LIB"mstr_standard"
BODY_TYPE"PLUMBING"
HDL_TAP"TRUE";
"B \NAC \NWC"4;
"S \NAC"
BN"12"162;
%"TAP"
"1","(-6075,4650)","0","mstr_standard","I264";
;
CDS_LIB"mstr_standard"
BODY_TYPE"PLUMBING"
HDL_TAP"TRUE";
"B \NAC \NWC"4;
"S \NAC"
BN"13"72;
%"TAP"
"1","(-6075,4700)","0","mstr_standard","I265";
;
CDS_LIB"mstr_standard"
BODY_TYPE"PLUMBING"
HDL_TAP"TRUE";
"B \NAC \NWC"4;
"S \NAC"
BN"14"71;
%"TAP"
"1","(-6075,4750)","0","mstr_standard","I266";
;
CDS_LIB"mstr_standard"
BODY_TYPE"PLUMBING"
HDL_TAP"TRUE";
"B \NAC \NWC"4;
"S \NAC"
BN"15"70;
%"TAP"
"1","(-6075,4850)","0","mstr_standard","I267";
;
CDS_LIB"mstr_standard"
BODY_TYPE"PLUMBING"
HDL_TAP"TRUE";
"B \NAC \NWC"4;
"S \NAC"
BN"17"68;
%"TAP"
"1","(-6075,4900)","0","mstr_standard","I268";
;
CDS_LIB"mstr_standard"
BODY_TYPE"PLUMBING"
HDL_TAP"TRUE";
"B \NAC \NWC"4;
"S \NAC"
BN"18"67;
%"TAP"
"1","(-6075,4800)","0","mstr_standard","I269";
;
CDS_LIB"mstr_standard"
BODY_TYPE"PLUMBING"
HDL_TAP"TRUE";
"B \NAC \NWC"4;
"S \NAC"
BN"16"69;
%"TAP"
"1","(-6075,4950)","0","mstr_standard","I270";
;
CDS_LIB"mstr_standard"
BODY_TYPE"PLUMBING"
HDL_TAP"TRUE";
"B \NAC \NWC"4;
"S \NAC"
BN"19"66;
%"TAP"
"1","(-6075,5000)","0","mstr_standard","I271";
;
CDS_LIB"mstr_standard"
BODY_TYPE"PLUMBING"
HDL_TAP"TRUE";
"B \NAC \NWC"4;
"S \NAC"
BN"20"65;
%"TAP"
"1","(-6075,5100)","0","mstr_standard","I272";
;
CDS_LIB"mstr_standard"
BODY_TYPE"PLUMBING"
HDL_TAP"TRUE";
"B \NAC \NWC"4;
"S \NAC"
BN"22"63;
%"TAP"
"1","(-6075,5050)","0","mstr_standard","I273";
;
CDS_LIB"mstr_standard"
BODY_TYPE"PLUMBING"
HDL_TAP"TRUE";
"B \NAC \NWC"4;
"S \NAC"
BN"21"64;
%"TAP"
"1","(-6075,5150)","0","mstr_standard","I274";
;
CDS_LIB"mstr_standard"
BODY_TYPE"PLUMBING"
HDL_TAP"TRUE";
"B \NAC \NWC"4;
"S \NAC"
BN"23"62;
%"TAP"
"1","(-6075,5200)","0","mstr_standard","I275";
;
CDS_LIB"mstr_standard"
BODY_TYPE"PLUMBING"
HDL_TAP"TRUE";
"B \NAC \NWC"4;
"S \NAC"
BN"24"61;
%"TAP"
"1","(-6075,5250)","0","mstr_standard","I276";
;
CDS_LIB"mstr_standard"
BODY_TYPE"PLUMBING"
HDL_TAP"TRUE";
"B \NAC \NWC"4;
"S \NAC"
BN"25"60;
%"TAP"
"1","(-6075,5300)","0","mstr_standard","I277";
;
CDS_LIB"mstr_standard"
BODY_TYPE"PLUMBING"
HDL_TAP"TRUE";
"B \NAC \NWC"4;
"S \NAC"
BN"26"115;
%"TAP"
"1","(-6075,5350)","0","mstr_standard","I278";
;
CDS_LIB"mstr_standard"
BODY_TYPE"PLUMBING"
HDL_TAP"TRUE";
"B \NAC \NWC"4;
"S \NAC"
BN"27"59;
%"TAP"
"1","(-6075,5400)","0","mstr_standard","I279";
;
CDS_LIB"mstr_standard"
BODY_TYPE"PLUMBING"
HDL_TAP"TRUE";
"B \NAC \NWC"4;
"S \NAC"
BN"28"58;
%"TAP"
"1","(-6075,5450)","0","mstr_standard","I280";
;
CDS_LIB"mstr_standard"
BODY_TYPE"PLUMBING"
HDL_TAP"TRUE";
"B \NAC \NWC"4;
"S \NAC"
BN"29"163;
%"TAP"
"1","(-6075,5500)","0","mstr_standard","I281";
;
CDS_LIB"mstr_standard"
BODY_TYPE"PLUMBING"
HDL_TAP"TRUE";
"B \NAC \NWC"4;
"S \NAC"
BN"30"57;
%"TAP"
"1","(-6075,5550)","0","mstr_standard","I282";
;
CDS_LIB"mstr_standard"
BODY_TYPE"PLUMBING"
HDL_TAP"TRUE";
"B \NAC \NWC"4;
"S \NAC"
BN"31"116;
%"GND"
"1","(-6450,1175)","0","mstr_symbols","I332";
;
SIZE"1B"
CDS_LIB"mstr_symbols"
BOM_COST"MEM"
VOLTAGE"0.0"
BODY_TYPE"PLUMBING"
HDL_POWER"GND";
"A\NAC"1;
%"Q_RES"
"2","(-6450,1425)","0","pure_quanta","I349";
;
LOCATION"R763"
$SEC"1"
CDS_SEC"1"
WATTAGE"1/16W"
MATERIAL"CHIP"
TOLERANCE"1%"
VALUE"35.7K"
PACK_TYPE"0402LF"
CDS_LIB"pure_quanta"
PART_NUMBER"CS33572FB01";
"A"
$PN"1"22;
"B"
$PN"2"1;
%"SCONN288_DDR506112002KQ"
"1","(-6925,3800)","0","pure_quanta","I350";
;
LOCATION"J19"
$SEC"1"
CDS_SEC"1"
PART_TYPE"SMLF"
MATERIAL"IO"
VALUE"SCONN288_DDR506112002KQ"
CDS_LMAN_SYM_OUTLINE"-450,1900,450,-1850"
NEEDS_NO_SIZE"TRUE"
CDS_LIB"pure_quanta"
PART_NUMBER"DFHST8FS479";
"PWR_GOOD||FAIL_N"
$PN"147"166;
"DQ31_A"
$PN"194"116;
"CB7_A"
$PN"205"23;
"CB4_A"
$PN"58"24;
"CB1_A"
$PN"53"25;
"CB7_B"
$PN"236"26;
"ALERT_N \B"
$PN"62"169;
"CA0_A"
$PN"66"27;
"CA0_B"
$PN"76"28;
"CA1_A"
$PN"211"29;
"CA1_B"
$PN"221"30;
"CA2_A"
$PN"68"31;
"CA2_B"
$PN"78"32;
"CA3_A"
$PN"213"33;
"CA3_B"
$PN"223"34;
"CA4_A"
$PN"70"35;
"CA4_B"
$PN"80"36;
"CA5_A"
$PN"215"37;
"CA5_B"
$PN"225"38;
"CA6_A"
$PN"72"117;
"CA6_B"
$PN"82"39;
"CB6_A"
$PN"203"40;
"CB5_A"
$PN"60"41;
"CB3_A"
$PN"198"42;
"CB2_A"
$PN"196"43;
"CB0_A"
$PN"51"44;
"CB6_B"
$PN"234"45;
"CB5_B"
$PN"91"46;
"CB4_B"
$PN"89"47;
"CB3_B"
$PN"243"48;
"CB2_B"
$PN"241"49;
"CB1_B"
$PN"98"50;
"CB0_B"
$PN"96"14;
"CK_C \B"
$PN"218"51;
"CK_T"
$PN"217"52;
"CS0_A_N"
$PN"64"53;
"CS0_B_N"
$PN"84"54;
"CS1_A_N"
$PN"209"55;
"CS1_B_N"
$PN"229"56;
"DQ30_A"
$PN"192"57;
"DQ29_A"
$PN"49"163;
"DQ28_A"
$PN"47"58;
"DQ27_A"
$PN"187"59;
"DQ26_A"
$PN"185"115;
"DQ25_A"
$PN"42"60;
"DQ24_A"
$PN"40"61;
"DQ23_A"
$PN"183"62;
"DQ22_A"
$PN"181"63;
"DQ21_A"
$PN"38"64;
"DQ20_A"
$PN"36"65;
"DQ19_A"
$PN"176"66;
"DQ18_A"
$PN"174"67;
"DQ17_A"
$PN"31"68;
"DQ16_A"
$PN"29"69;
"DQ15_A"
$PN"172"70;
"DQ14_A"
$PN"170"71;
"DQ13_A"
$PN"27"72;
"DQ12_A"
$PN"25"162;
"DQ11_A"
$PN"165"73;
"DQ10_A"
$PN"163"74;
"DQ9_A"
$PN"20"161;
"DQ8_A"
$PN"18"160;
"DQ7_A"
$PN"161"159;
"DQ6_A"
$PN"159"158;
"DQ5_A"
$PN"16"75;
"DQ4_A"
$PN"14"76;
"DQ3_A"
$PN"154"77;
"DQ2_A"
$PN"152"78;
"DQ1_A"
$PN"9"79;
"DQ0_A"
$PN"7"80;
"DQ31_B"
$PN"287"81;
"DQ30_B"
$PN"285"82;
"DQ29_B"
$PN"142"83;
"DQ28_B"
$PN"140"84;
"DQ27_B"
$PN"280"85;
"DQ26_B"
$PN"278"86;
"DQ25_B"
$PN"135"87;
"DQ24_B"
$PN"133"88;
"DQ23_B"
$PN"276"89;
"DQ22_B"
$PN"274"90;
"DQ21_B"
$PN"131"91;
"DQ20_B"
$PN"129"92;
"DQ19_B"
$PN"269"93;
"DQ18_B"
$PN"267"94;
"DQ17_B"
$PN"124"95;
"DQ16_B"
$PN"122"96;
"DQ15_B"
$PN"265"97;
"DQ14_B"
$PN"263"98;
"DQ13_B"
$PN"120"99;
"DQ12_B"
$PN"118"100;
"DQ11_B"
$PN"258"101;
"DQ10_B"
$PN"256"102;
"DQ9_B"
$PN"113"103;
"DQ8_B"
$PN"111"104;
"DQ7_B"
$PN"254"105;
"DQ6_B"
$PN"252"106;
"DQ5_B"
$PN"109"107;
"DQ4_B"
$PN"107"108;
"DQ3_B"
$PN"247"109;
"DQ2_B"
$PN"245"110;
"DQ1_B"
$PN"102"111;
"DQ0_B"
$PN"100"112;
"HAS"
$PN"148"171;
"HSCL"
$PN"4"17;
"HSDA"
$PN"5"170;
"LBD||RSP_A_N"
$PN"86"165;
"LBS||RSP_B_N"
$PN"87"113;
"PAR_A"
$PN"74"164;
"PAR_B"
$PN"227"114;
"RESET_N \B"
$PN"207"16;
"RFU6"
$PN"232"0;
"RFU5"
$PN"231"0;
"RFU4"
$PN"220"0;
"RFU3"
$PN"150"0;
"RFU2"
$PN"149"0;
"RFU1"
$PN"144"0;
"RFU0"
$PN"2"0;
"VIN_MGMT"
$PN"3"172;
%"SCONN288_DDR506112002KQ"
"3","(-1350,3700)","0","pure_quanta","I352";
;
LOCATION"J19"
$SEC"3"
CDS_SEC"3"
MATERIAL"IO"
VALUE"SCONN288_DDR506112002KQ"
PART_TYPE"SMLF"
CDS_LMAN_SYM_OUTLINE"-450,1800,450,-1750"
NEEDS_NO_SIZE"TRUE"
CDS_LIB"pure_quanta"
PART_NUMBER"DFHST8FS479";
"G3"
$PN"G3"20;
"G2"
$PN"G2"20;
"G1"
$PN"G1"20;
"VSS62"
$PN"141"20;
"VSS61"
$PN"139"20;
"VSS60"
$PN"136"20;
"VSS58"
$PN"132"20;
"VSS104"
$PN"240"21;
"VSS102"
$PN"235"21;
"VSS100"
$PN"230"21;
"VIN_BULK2"
$PN"146"18;
"VIN_BULK1"
$PN"145"18;
"VIN_BULK0"
$PN"1"18;
"VSS126"
$PN"288"21;
"VSS125"
$PN"286"21;
"VSS124"
$PN"284"21;
"VSS123"
$PN"281"21;
"VSS122"
$PN"279"21;
"VSS121"
$PN"277"21;
"VSS120"
$PN"275"21;
"VSS119"
$PN"273"21;
"VSS118"
$PN"270"21;
"VSS117"
$PN"268"21;
"VSS116"
$PN"266"21;
"VSS115"
$PN"264"21;
"VSS114"
$PN"262"21;
"VSS113"
$PN"259"21;
"VSS112"
$PN"257"21;
"VSS111"
$PN"255"21;
"VSS110"
$PN"253"21;
"VSS109"
$PN"251"21;
"VSS108"
$PN"248"21;
"VSS107"
$PN"246"21;
"VSS106"
$PN"244"21;
"VSS105"
$PN"242"21;
"VSS103"
$PN"237"21;
"VSS101"
$PN"233"21;
"VSS99"
$PN"228"21;
"VSS98"
$PN"226"21;
"VSS97"
$PN"224"21;
"VSS96"
$PN"222"21;
"VSS95"
$PN"219"21;
"VSS94"
$PN"216"21;
"VSS93"
$PN"214"21;
"VSS92"
$PN"212"21;
"VSS91"
$PN"210"21;
"VSS90"
$PN"208"21;
"VSS89"
$PN"206"21;
"VSS88"
$PN"204"21;
"VSS87"
$PN"202"21;
"VSS86"
$PN"199"21;
"VSS85"
$PN"197"21;
"VSS84"
$PN"195"21;
"VSS83"
$PN"193"21;
"VSS82"
$PN"191"21;
"VSS81"
$PN"188"21;
"VSS80"
$PN"186"21;
"VSS79"
$PN"184"21;
"VSS78"
$PN"182"21;
"VSS77"
$PN"180"21;
"VSS76"
$PN"177"21;
"VSS75"
$PN"175"21;
"VSS74"
$PN"173"21;
"VSS73"
$PN"171"21;
"VSS72"
$PN"169"21;
"VSS71"
$PN"166"21;
"VSS70"
$PN"164"21;
"VSS69"
$PN"162"21;
"VSS68"
$PN"160"21;
"VSS67"
$PN"158"21;
"VSS66"
$PN"155"21;
"VSS65"
$PN"153"21;
"VSS64"
$PN"151"21;
"VSS63"
$PN"143"20;
"VSS59"
$PN"134"20;
"VSS57"
$PN"130"20;
"VSS56"
$PN"128"20;
"VSS55"
$PN"125"20;
"VSS54"
$PN"123"20;
"VSS53"
$PN"121"20;
"VSS52"
$PN"119"20;
"VSS51"
$PN"117"20;
"VSS50"
$PN"114"20;
"VSS49"
$PN"112"20;
"VSS48"
$PN"110"20;
"VSS47"
$PN"108"20;
"VSS46"
$PN"106"20;
"VSS45"
$PN"103"20;
"VSS44"
$PN"101"20;
"VSS43"
$PN"99"20;
"VSS42"
$PN"97"20;
"VSS41"
$PN"95"20;
"VSS40"
$PN"92"20;
"VSS39"
$PN"90"20;
"VSS38"
$PN"88"20;
"VSS37"
$PN"85"20;
"VSS36"
$PN"83"20;
"VSS35"
$PN"81"20;
"VSS34"
$PN"79"20;
"VSS33"
$PN"77"20;
"VSS32"
$PN"75"20;
"VSS31"
$PN"73"20;
"VSS30"
$PN"71"20;
"VSS29"
$PN"69"20;
"VSS28"
$PN"67"20;
"VSS27"
$PN"65"20;
"VSS26"
$PN"63"20;
"VSS25"
$PN"61"20;
"VSS24"
$PN"59"20;
"VSS23"
$PN"57"20;
"VSS22"
$PN"54"20;
"VSS21"
$PN"52"20;
"VSS20"
$PN"50"20;
"VSS19"
$PN"48"20;
"VSS18"
$PN"46"20;
"VSS17"
$PN"43"20;
"VSS16"
$PN"41"20;
"VSS15"
$PN"39"20;
"VSS14"
$PN"37"20;
"VSS13"
$PN"35"20;
"VSS12"
$PN"32"20;
"VSS11"
$PN"30"20;
"VSS10"
$PN"28"20;
"VSS9"
$PN"26"20;
"VSS8"
$PN"24"20;
"VSS7"
$PN"21"20;
"VSS6"
$PN"19"20;
"VSS5"
$PN"17"20;
"VSS4"
$PN"15"20;
"VSS3"
$PN"13"20;
"VSS2"
$PN"10"20;
"VSS1"
$PN"8"20;
"VSS0"
$PN"6"20;
%"GND"
"1","(-8600,3150)","0","mstr_symbols","I361";
;
BOM_COST"MEM"
SIZE"1B"
CDS_LIB"mstr_symbols"
VOLTAGE"0"
ROOM"MEM_EFGH_DECOUPLING_CAPS"
BODY_TYPE"PLUMBING"
HDL_POWER"GND";
"A\NAC"2;
%"Q_CAP"
"1","(-8600,3375)","2","pure_quanta","I362";
;
LOCATION"C100"
$SEC"1"
CDS_SEC"1"
PACK_TYPE"0402"
MATERIAL"X7R"
VALUE"0.1UF"
VOLTAGE"25V"
TOLERANCE"10%"
CDS_LIB"pure_quanta"
BOM_COST"MEM"
ROOM""
PART_NUMBER"CH4104K1B00";
"B"
$PN"2"2;
"A"
$PN"1"172;
%"Q_RES"
"2","(-8375,2450)","0","pure_quanta","I367";
;
LOCATION"R92"
$SEC"1"
CDS_SEC"1"
TOLERANCE"1%"
WATTAGE"1/16W"
MATERIAL"EMPTY"
VALUE"1K"
PACK_TYPE"0402LF"
BOM_COST"MEM"
CDS_LIB"pure_quanta"
ROOM""
PART_NUMBER"CS21002FB06";
"A"
$PN"1"3;
"B"
$PN"2"166;
%"VCC_CORE"
"1","(-8375,2625)","0","mstr_symbols","I368";
;
HDL_POWER"P3V3"
CDS_LIB"mstr_symbols"
VOLTAGE"3.3"
ROOM"PVCCINFAON_CPU0_CTRL";
"A"3;
%"Q_RES"
"1","(-8500,2300)","2","pure_quanta","I369";
;
LOCATION"R294"
$SEC"1"
CDS_SEC"1"
VALUE"1K"
TOLERANCE"1%"
BOM_COST"MEM"
CDS_LIB"pure_quanta"
WATTAGE"1/16W"
MATERIAL"CHIP"
PACK_TYPE"0402LF"
ROOM""
PART_NUMBER"CS21002FB06";
"B"
$PN"2"167;
"A"
$PN"1"166;
%"TAP"
"1","(-3500,4575)","0","mstr_standard","I375";
;
CDS_LIB"mstr_standard"
BODY_TYPE"PLUMBING"
HDL_TAP"TRUE";
"B \NAC \NWC"5;
"S \NAC"
BN"9"157;
%"TAP"
"1","(-3500,4475)","0","mstr_standard","I376";
;
CDS_LIB"mstr_standard"
BODY_TYPE"PLUMBING"
HDL_TAP"TRUE";
"B \NAC \NWC"5;
"S \NAC"
BN"8"148;
%"TAP"
"1","(-3500,4375)","0","mstr_standard","I377";
;
CDS_LIB"mstr_standard"
BODY_TYPE"PLUMBING"
HDL_TAP"TRUE";
"B \NAC \NWC"5;
"S \NAC"
BN"7"118;
%"TAP"
"1","(-3500,4275)","0","mstr_standard","I378";
;
CDS_LIB"mstr_standard"
BODY_TYPE"PLUMBING"
HDL_TAP"TRUE";
"B \NAC \NWC"5;
"S \NAC"
BN"6"143;
%"TAP"
"1","(-3700,4525)","0","mstr_standard","I379";
;
CDS_LIB"mstr_standard"
BODY_TYPE"PLUMBING"
HDL_TAP"TRUE";
"B \NAC \NWC"8;
"S \NAC"
BN"8"149;
%"TAP"
"1","(-3700,4625)","0","mstr_standard","I380";
;
CDS_LIB"mstr_standard"
BODY_TYPE"PLUMBING"
HDL_TAP"TRUE";
"B \NAC \NWC"8;
"S \NAC"
BN"9"150;
%"TAP"
"1","(-3700,4425)","0","mstr_standard","I381";
;
CDS_LIB"mstr_standard"
BODY_TYPE"PLUMBING"
HDL_TAP"TRUE";
"B \NAC \NWC"8;
"S \NAC"
BN"7"146;
%"TAP"
"1","(-3700,4325)","0","mstr_standard","I382";
;
CDS_LIB"mstr_standard"
BODY_TYPE"PLUMBING"
HDL_TAP"TRUE";
"B \NAC \NWC"8;
"S \NAC"
BN"6"119;
%"TAP"
"1","(-3500,4175)","0","mstr_standard","I383";
;
CDS_LIB"mstr_standard"
BODY_TYPE"PLUMBING"
HDL_TAP"TRUE";
"B \NAC \NWC"5;
"S \NAC"
BN"5"139;
%"TAP"
"1","(-3500,4075)","0","mstr_standard","I384";
;
CDS_LIB"mstr_standard"
BODY_TYPE"PLUMBING"
HDL_TAP"TRUE";
"B \NAC \NWC"5;
"S \NAC"
BN"4"135;
%"TAP"
"1","(-3500,3975)","0","mstr_standard","I385";
;
CDS_LIB"mstr_standard"
BODY_TYPE"PLUMBING"
HDL_TAP"TRUE";
"B \NAC \NWC"5;
"S \NAC"
BN"3"131;
%"TAP"
"1","(-3500,3875)","0","mstr_standard","I386";
;
CDS_LIB"mstr_standard"
BODY_TYPE"PLUMBING"
HDL_TAP"TRUE";
"B \NAC \NWC"5;
"S \NAC"
BN"2"127;
%"TAP"
"1","(-3500,3775)","0","mstr_standard","I387";
;
CDS_LIB"mstr_standard"
BODY_TYPE"PLUMBING"
HDL_TAP"TRUE";
"B \NAC \NWC"5;
"S \NAC"
BN"1"152;
%"TAP"
"1","(-3700,4225)","0","mstr_standard","I388";
;
CDS_LIB"mstr_standard"
BODY_TYPE"PLUMBING"
HDL_TAP"TRUE";
"B \NAC \NWC"8;
"S \NAC"
BN"5"140;
%"TAP"
"1","(-3700,4125)","0","mstr_standard","I389";
;
CDS_LIB"mstr_standard"
BODY_TYPE"PLUMBING"
HDL_TAP"TRUE";
"B \NAC \NWC"8;
"S \NAC"
BN"4"136;
%"TAP"
"1","(-3700,4025)","0","mstr_standard","I390";
;
CDS_LIB"mstr_standard"
BODY_TYPE"PLUMBING"
HDL_TAP"TRUE";
"B \NAC \NWC"8;
"S \NAC"
BN"3"132;
%"TAP"
"1","(-3700,3925)","0","mstr_standard","I391";
;
CDS_LIB"mstr_standard"
BODY_TYPE"PLUMBING"
HDL_TAP"TRUE";
"B \NAC \NWC"8;
"S \NAC"
BN"2"128;
%"TAP"
"1","(-3700,3825)","0","mstr_standard","I392";
;
CDS_LIB"mstr_standard"
BODY_TYPE"PLUMBING"
HDL_TAP"TRUE";
"B \NAC \NWC"8;
"S \NAC"
BN"1"151;
%"TAP"
"1","(-3500,3675)","0","mstr_standard","I393";
;
CDS_LIB"mstr_standard"
BODY_TYPE"PLUMBING"
HDL_TAP"TRUE";
"B \NAC \NWC"5;
"S \NAC"
BN"0"153;
%"TAP"
"1","(-3500,3525)","0","mstr_standard","I394";
;
CDS_LIB"mstr_standard"
BODY_TYPE"PLUMBING"
HDL_TAP"TRUE";
"B \NAC \NWC"7;
"S \NAC"
BN"9"155;
%"TAP"
"1","(-3500,3425)","0","mstr_standard","I395";
;
CDS_LIB"mstr_standard"
BODY_TYPE"PLUMBING"
HDL_TAP"TRUE";
"B \NAC \NWC"7;
"S \NAC"
BN"8"120;
%"TAP"
"1","(-3500,3325)","0","mstr_standard","I396";
;
CDS_LIB"mstr_standard"
BODY_TYPE"PLUMBING"
HDL_TAP"TRUE";
"B \NAC \NWC"7;
"S \NAC"
BN"7"147;
%"TAP"
"1","(-3700,3575)","0","mstr_standard","I397";
;
CDS_LIB"mstr_standard"
BODY_TYPE"PLUMBING"
HDL_TAP"TRUE";
"B \NAC \NWC"6;
"S \NAC"
BN"9"154;
%"TAP"
"1","(-3700,3725)","0","mstr_standard","I398";
;
CDS_LIB"mstr_standard"
BODY_TYPE"PLUMBING"
HDL_TAP"TRUE";
"B \NAC \NWC"8;
"S \NAC"
BN"0"122;
%"TAP"
"1","(-3700,3375)","0","mstr_standard","I399";
;
CDS_LIB"mstr_standard"
BODY_TYPE"PLUMBING"
HDL_TAP"TRUE";
"B \NAC \NWC"6;
"S \NAC"
BN"7"121;
%"TAP"
"1","(-3700,3475)","0","mstr_standard","I400";
;
CDS_LIB"mstr_standard"
BODY_TYPE"PLUMBING"
HDL_TAP"TRUE";
"B \NAC \NWC"6;
"S \NAC"
BN"8"156;
%"TAP"
"1","(-3700,3275)","0","mstr_standard","I401";
;
CDS_LIB"mstr_standard"
BODY_TYPE"PLUMBING"
HDL_TAP"TRUE";
"B \NAC \NWC"6;
"S \NAC"
BN"6"145;
%"TAP"
"1","(-3500,3225)","0","mstr_standard","I402";
;
CDS_LIB"mstr_standard"
BODY_TYPE"PLUMBING"
HDL_TAP"TRUE";
"B \NAC \NWC"7;
"S \NAC"
BN"6"144;
%"TAP"
"1","(-3500,3125)","0","mstr_standard","I403";
;
CDS_LIB"mstr_standard"
BODY_TYPE"PLUMBING"
HDL_TAP"TRUE";
"B \NAC \NWC"7;
"S \NAC"
BN"5"141;
%"TAP"
"1","(-3500,3025)","0","mstr_standard","I404";
;
CDS_LIB"mstr_standard"
BODY_TYPE"PLUMBING"
HDL_TAP"TRUE";
"B \NAC \NWC"7;
"S \NAC"
BN"4"137;
%"TAP"
"1","(-3500,2925)","0","mstr_standard","I405";
;
CDS_LIB"mstr_standard"
BODY_TYPE"PLUMBING"
HDL_TAP"TRUE";
"B \NAC \NWC"7;
"S \NAC"
BN"3"133;
%"TAP"
"1","(-3500,2825)","0","mstr_standard","I406";
;
CDS_LIB"mstr_standard"
BODY_TYPE"PLUMBING"
HDL_TAP"TRUE";
"B \NAC \NWC"7;
"S \NAC"
BN"2"129;
%"TAP"
"1","(-3500,2725)","0","mstr_standard","I407";
;
CDS_LIB"mstr_standard"
BODY_TYPE"PLUMBING"
HDL_TAP"TRUE";
"B \NAC \NWC"7;
"S \NAC"
BN"1"125;
%"TAP"
"1","(-3700,3175)","0","mstr_standard","I408";
;
CDS_LIB"mstr_standard"
BODY_TYPE"PLUMBING"
HDL_TAP"TRUE";
"B \NAC \NWC"6;
"S \NAC"
BN"5"142;
%"TAP"
"1","(-3700,3075)","0","mstr_standard","I409";
;
CDS_LIB"mstr_standard"
BODY_TYPE"PLUMBING"
HDL_TAP"TRUE";
"B \NAC \NWC"6;
"S \NAC"
BN"4"138;
%"TAP"
"1","(-3700,2875)","0","mstr_standard","I410";
;
CDS_LIB"mstr_standard"
BODY_TYPE"PLUMBING"
HDL_TAP"TRUE";
"B \NAC \NWC"6;
"S \NAC"
BN"2"130;
%"TAP"
"1","(-3700,2975)","0","mstr_standard","I411";
;
CDS_LIB"mstr_standard"
BODY_TYPE"PLUMBING"
HDL_TAP"TRUE";
"B \NAC \NWC"6;
"S \NAC"
BN"3"134;
%"TAP"
"1","(-3700,2775)","0","mstr_standard","I412";
;
CDS_LIB"mstr_standard"
BODY_TYPE"PLUMBING"
HDL_TAP"TRUE";
"B \NAC \NWC"6;
"S \NAC"
BN"1"126;
%"TAP"
"1","(-3500,2625)","0","mstr_standard","I413";
;
CDS_LIB"mstr_standard"
BODY_TYPE"PLUMBING"
HDL_TAP"TRUE";
"B \NAC \NWC"7;
"S \NAC"
BN"0"123;
%"TAP"
"1","(-3700,2675)","0","mstr_standard","I414";
;
CDS_LIB"mstr_standard"
BODY_TYPE"PLUMBING"
HDL_TAP"TRUE";
"B \NAC \NWC"6;
"S \NAC"
BN"0"124;
%"SCONN288_DDR506112002KQ"
"2","(-4650,3625)","0","pure_quanta","I415";
;
LOCATION"J19"
$SEC"2"
CDS_SEC"2"
VALUE"SCONN288_DDR506112002KQ"
PART_TYPE"SMLF"
MATERIAL"IO"
CDS_LMAN_SYM_OUTLINE"-600,1150,600,-1150"
NEEDS_NO_SIZE"TRUE"
CDS_LIB"pure_quanta"
PART_NUMBER"DFHST8FS479";
"DQS7_A_C||TDQS7_A_C \B"
$PN"178"118;
"DQS6_A_T||TDQS6_A_T"
$PN"168"119;
"DQS8_B_T||TDQS8_B_T"
$PN"283"156;
"DQS8_B_C||TDQS8_B_C \B"
$PN"282"120;
"DQS7_B_T||TDQS7_B_T"
$PN"272"121;
"DQS0_A_C \B"
$PN"12"153;
"DQS0_A_T"
$PN"11"122;
"DQS0_B_C \B"
$PN"105"123;
"DQS0_B_T"
$PN"104"124;
"DQS1_A_C \B"
$PN"23"152;
"DQS1_A_T"
$PN"22"151;
"DQS1_B_C \B"
$PN"116"125;
"DQS1_B_T"
$PN"115"126;
"DQS2_A_C \B"
$PN"34"127;
"DQS2_A_T"
$PN"33"128;
"DQS2_B_C \B"
$PN"127"129;
"DQS2_B_T"
$PN"126"130;
"DQS3_A_C \B"
$PN"45"131;
"DQS3_A_T"
$PN"44"132;
"DQS3_B_C \B"
$PN"138"133;
"DQS3_B_T"
$PN"137"134;
"DQS4_A_C \B"
$PN"56"135;
"DQS4_A_T"
$PN"55"136;
"DQS4_B_C \B"
$PN"238"137;
"DQS4_B_T"
$PN"239"138;
"DQS5_A_C||TDQS5_A_C||DQS5_A_T||TDQS5_A_T \B"
$PN"156"139;
"DQS5_A_T||TDQS5_A_T"
$PN"157"140;
"DQS5_B_C||TDQS5_B_C \B"
$PN"249"141;
"DQS5_B_T||TDQS5_B_T"
$PN"250"142;
"DQS6_A_C||TDQS6_A_C||DQS6_A_T||TDQS6_A_T \B"
$PN"167"143;
"DQS6_B_C||TDQS6_B_C \B"
$PN"260"144;
"DQS6_B_T||TDQS6_B_T"
$PN"261"145;
"DQS7_A_T||TDQS7_A_T"
$PN"179"146;
"DQS7_B_C||TDQS7_B_C \B"
$PN"271"147;
"DQS8_A_C||TDQS8_A_C \B"
$PN"189"148;
"DQS8_A_T||TDQS8_A_T"
$PN"190"149;
"DQS9_A_C||TDQS9_A_C \B"
$PN"200"157;
"DQS9_A_T||TDQS9_A_T"
$PN"201"150;
"DQS9_B_C||TDQS9_B_C \B"
$PN"94"155;
"DQS9_B_T||TDQS9_B_T||DBI4_B_N"
$PN"93"154;
%"GND"
"1","(-2950,5225)","0","pure_quanta_power","I416";
;
CDS_LIB"pure_quanta_power"
BOM_COST"MEM"
SIZE"1B"
ROOM"MEM_EFGH_DECOUPLING_CAPS"
HDL_POWER"GND";
"A<SIZE-1..0>\NAC"19;
%"Q_CAP"
"1","(-2950,5575)","2","pure_quanta","I417";
;
LOCATION"C149"
$SEC"1"
CDS_SEC"1"
TOLERANCE"10%"
MATERIAL"X6S"
PACK_TYPE"C0805"
VOLTAGE"25V"
VALUE"10UF"
CDS_LIB"pure_quanta"
BOM_COST"MEM"
ROOM""
PART_NUMBER"CH6104KEA00";
"B"
$PN"2"19;
"A"
$PN"1"18;
%"Q_CAP"
"1","(-2375,5575)","2","pure_quanta","I418";
;
LOCATION"C150"
$SEC"1"
CDS_SEC"1"
TOLERANCE"10%"
PACK_TYPE"C0805"
VOLTAGE"25V"
VALUE"10UF"
MATERIAL"X6S"
CDS_LIB"pure_quanta"
BOM_COST"MEM"
ROOM""
PART_NUMBER"CH6104KEA00";
"B"
$PN"2"19;
"A"
$PN"1"18;
%"UNIVERSAL_POWER"
"1","(-2950,5900)","0","pure_quanta_power","I419";
;
HDL_POWER"P12V_MEM_CPU0"
BOM_COST"VR_SYSTEM"
CDS_LIB"pure_quanta_power";
"A"18;
%"Q_RES"
"1","(-7825,2775)","0","pure_quanta","I421";
;
LOCATION"R1"
$SEC"1"
CDS_SEC"1"
VALUE"49.9"
CDS_LIB"pure_quanta"
TOLERANCE"1%"
WATTAGE"1/16W"
PACK_TYPE"0402LF"
MATERIAL"CHIP"
PART_NUMBER"CS04992FB07";
"B"
$PN"2"17;
"A"
$PN"1"15;
%"Q_RES"
"1","(-8175,3000)","0","pure_quanta","I422";
;
LOCATION"R1676"
SEC"1"
VALUE"10"
MATERIAL"CHIP"
PACK_TYPE"0402LF"
WATTAGE"1/16W"
TOLERANCE"1%"
CDS_LIB"pure_quanta"
SEC_TYPE"0402LF"
PART_NUMBER"CS01002FB07";
"B"
$PN"2"170;
"A"
$PN"1"168;
END.
